# TIMECARD (Time Appliance Project (Time Card)) — schematic netlist excerpt (pin names and nets, part order shuffled) for the footprints in the layout excerpt that follows; sources: Cadence DE-HDL packaged netlist, KiCad conversion of R4006-B0001-02_R01.brd

R106  RESISTOR  0OHM -  pkg SMC_0402R_H016  page 21 : \1\ = MUX_USB_DP ; \2\ = MAC_USB_DP
R355  RESISTOR  10KOHM 1%  pkg SMC_0402R_H016  page 13 : \1\ = MHZ200CLKN_CLKIN ; \2\ = XP2R5V_FPGA

(kicad_pcb
	(version 20260206)
	(generator "pcbnew")
	(generator_version "10.0")
	(general
		(thickness 1.6)
		(legacy_teardrops no)
	)
	(paper "A4")
	(title_block
		(title "timecard-production-celestica-r4006 — R4006-B0001-02_R01.brd")
		(comment 1 "Time Appliance Project (Time Card) / footprints 1063-1064 of 1113")
	)
	(layers
		(0 "F.Cu" signal "TOP")
		(4 "In1.Cu" signal "L02_GND1")
		(6 "In2.Cu" signal "L03_SIG1")
		(8 "In3.Cu" signal "L04_GND2")
		(10 "In4.Cu" signal "L05_VCC1")
		(12 "In5.Cu" signal "L06_VCC2")
		(14 "In6.Cu" signal "L07_GND3")
		(16 "In7.Cu" signal "L08_SIG2")
		(18 "In8.Cu" signal "L09_GND4")
		(2 "B.Cu" signal "BOTTOM")
		(9 "F.Adhes" user "F.Adhesive")
		(11 "B.Adhes" user "B.Adhesive")
		(13 "F.Paste" user "Package Geometry/Pastemask Top")
		(15 "B.Paste" user "Package Geometry/Pastemask Bottom")
		(5 "F.SilkS" user "Ref Des/Silkscreen Top")
		(7 "B.SilkS" user "Ref Des/Silkscreen Bottom")
		(1 "F.Mask" user "Board Geometry/Soldermask Top")
		(3 "B.Mask" user "Board Geometry/Soldermask Bottom")
		(17 "Dwgs.User" user "User.Drawings")
		(19 "Cmts.User" user "User.Comments")
		(21 "Eco1.User" user "User.Eco1")
		(23 "Eco2.User" user "User.Eco2")
		(25 "Edge.Cuts" user "Board Geometry/Outline")
		(27 "Margin" user)
		(31 "F.CrtYd" user "Package Geometry/Place Bound Top")
		(29 "B.CrtYd" user "Package Geometry/Place Bound Bottom")
		(35 "F.Fab" user "Ref Des/Assembly Top")
		(33 "B.Fab" user "Ref Des/Assembly Bottom")
	)
	(footprint ""
		(layer "B.Cu")
		(at 110.998 -27.94 90)
		(property "Reference" "R355"
			(at -2.667 -0.03937 270)
			(unlocked yes)
			(layer "B.SilkS")
			(effects
				(font
					(size 0.7874 0.5842)
					(thickness 0.1524)
				)
				(justify mirror)
			)
		)
		(property "Value" "VAL*"
			(at -0.02032 2.13233 90)
			(unlocked yes)
			(layer "B.Fab")
			(hide yes)
			(effects
				(font
					(size 0.7874 0.5842)
					(thickness 0.1524)
				)
				(justify mirror)
			)
		)
		(property "Tolerance" "TOL*"
			(at -0.044704 3.05435 90)
			(unlocked yes)
			(layer "Cmts.User")
			(hide yes)
			(effects
				(font
					(size 0.7874 0.5842)
					(thickness 0.1524)
				)
				(justify mirror)
			)
		)
		(property "User Part Number" "PARTNUM*"
			(at -0.02032 4.024884 90)
			(unlocked yes)
			(layer "Cmts.User")
			(hide yes)
			(effects
				(font
					(size 0.7874 0.5842)
					(thickness 0.1524)
				)
				(justify mirror)
			)
		)
		(property "Device Type" "RESISTOR-G155-11002-01,10KOHM,A"
			(at -0.008382 1.210564 90)
			(unlocked yes)
			(layer "B.Fab")
			(hide yes)
			(effects
				(font
					(size 0.7874 0.5842)
					(thickness 0.1524)
				)
				(justify mirror)
			)
		)
		(duplicate_pad_numbers_are_jumpers no)
		(fp_line
			(start 1.143 -0.5588)
			(end 1.143 0.5588)
			(stroke
				(width 0.1)
				(type default)
			)
			(layer "B.SilkS")
		)
		(fp_line
			(start -1.143 -0.5588)
			(end 1.143 -0.5588)
			(stroke
				(width 0.1)
				(type default)
			)
			(layer "B.SilkS")
		)
		(fp_line
			(start 1.143 0.5588)
			(end -1.143 0.5588)
			(stroke
				(width 0.1)
				(type default)
			)
			(layer "B.SilkS")
		)
		(fp_line
			(start -1.143 0.5588)
			(end -1.143 -0.5588)
			(stroke
				(width 0.1)
				(type default)
			)
			(layer "B.SilkS")
		)
		(fp_poly
			(pts
				(xy 1.143 0.5588) (xy -1.143 0.5588) (xy -1.143 -0.5588) (xy 1.143 -0.5588)
			)
			(stroke
				(width 0)
				(type default)
			)
			(fill no)
			(layer "B.CrtYd")
		)
		(fp_line
			(start 0.508 -0.3048)
			(end 0.508 0.3048)
			(stroke
				(width 0.1)
				(type default)
			)
			(layer "B.Fab")
		)
		(fp_line
			(start -0.508 -0.3048)
			(end 0.508 -0.3048)
			(stroke
				(width 0.1)
				(type default)
			)
			(layer "B.Fab")
		)
		(fp_line
			(start 0.508 0.3048)
			(end -0.508 0.3048)
			(stroke
				(width 0.1)
				(type default)
			)
			(layer "B.Fab")
		)
		(fp_line
			(start -0.508 0.3048)
			(end -0.508 -0.3048)
			(stroke
				(width 0.1)
				(type default)
			)
			(layer "B.Fab")
		)
		(pad "1" smd rect
			(at 0.5334 0 270)
			(size 0.7112 0.6096)
			(layers "B.Cu" "B.Mask" "B.Paste")
			(net "MHZ200CLKN_CLKIN")
		)
		(pad "2" smd rect
			(at -0.5334 0 270)
			(size 0.7112 0.6096)
			(layers "B.Cu" "B.Mask" "B.Paste")
			(net "XP2R5V_FPGA")
		)
		(zone
			(layer "B.Cu")
			(hatch none 0.5)
			(connect_pads
				(clearance 0)
			)
			(min_thickness 0.25)
			(keepout
				(tracks allowed)
				(vias not_allowed)
				(pads allowed)
				(copperpour not_allowed)
				(footprints allowed)
			)
			(placement
				(enabled no)
				(sheetname "")
			)
			(fill
				(thermal_gap 0.5)
				(thermal_bridge_width 0.5)
				(island_removal_mode 0)
			)
			(polygon
				(pts
					(xy 111.3028 -28.0162) (xy 110.6932 -28.0162) (xy 110.6932 -27.8638) (xy 111.3028 -27.8638)
				)
			)
		)
		(zone
			(layer "B.Cu")
			(hatch none 0.5)
			(connect_pads
				(clearance 0)
			)
			(min_thickness 0.25)
			(keepout
				(tracks not_allowed)
				(vias allowed)
				(pads allowed)
				(copperpour not_allowed)
				(footprints allowed)
			)
			(placement
				(enabled no)
				(sheetname "")
			)
			(fill
				(thermal_gap 0.5)
				(thermal_bridge_width 0.5)
				(island_removal_mode 0)
			)
			(polygon
				(pts
					(xy 111.3028 -28.0162) (xy 110.6932 -28.0162) (xy 110.6932 -27.8638) (xy 111.3028 -27.8638)
				)
			)
		)
	)
	(footprint ""
		(layer "B.Cu")
		(at 90.2716 -47.916846 180)
		(property "Reference" "R106"
			(at -0.762 2.500884 0)
			(unlocked yes)
			(layer "B.SilkS")
			(effects
				(font
					(size 0.7874 0.5842)
					(thickness 0.1524)
				)
				(justify mirror)
			)
		)
		(property "Value" "VAL*"
			(at -0.02032 2.13233 180)
			(unlocked yes)
			(layer "B.Fab")
			(hide yes)
			(effects
				(font
					(size 0.7874 0.5842)
					(thickness 0.1524)
				)
				(justify mirror)
			)
		)
		(property "Tolerance" "TOL*"
			(at -0.044704 3.05435 180)
			(unlocked yes)
			(layer "Cmts.User")
			(hide yes)
			(effects
				(font
					(size 0.7874 0.5842)
					(thickness 0.1524)
				)
				(justify mirror)
			)
		)
		(property "User Part Number" "PARTNUM*"
			(at -0.02032 4.024884 180)
			(unlocked yes)
			(layer "Cmts.User")
			(hide yes)
			(effects
				(font
					(size 0.7874 0.5842)
					(thickness 0.1524)
				)
				(justify mirror)
			)
		)
		(property "Device Type" "RESISTOR-G155-100R0-J0,0OHM,-"
			(at -0.008382 1.210564 180)
			(unlocked yes)
			(layer "B.Fab")
			(hide yes)
			(effects
				(font
					(size 0.7874 0.5842)
					(thickness 0.1524)
				)
				(justify mirror)
			)
		)
		(duplicate_pad_numbers_are_jumpers no)
		(fp_line
			(start 1.143 0.5588)
			(end -1.143 0.5588)
			(stroke
				(width 0.1)
				(type default)
			)
			(layer "B.SilkS")
		)
		(fp_line
			(start 1.143 -0.5588)
			(end 1.143 0.5588)
			(stroke
				(width 0.1)
				(type default)
			)
			(layer "B.SilkS")
		)
		(fp_line
			(start -1.143 0.5588)
			(end -1.143 -0.5588)
			(stroke
				(width 0.1)
				(type default)
			)
			(layer "B.SilkS")
		)
		(fp_line
			(start -1.143 -0.5588)
			(end 1.143 -0.5588)
			(stroke
				(width 0.1)
				(type default)
			)
			(layer "B.SilkS")
		)
		(fp_rect
			(start 1.143 -0.5588)
			(end -1.143 0.5588)
			(stroke
				(width 0)
				(type default)
			)
			(fill no)
			(layer "B.CrtYd")
		)
		(fp_line
			(start 0.508 0.3048)
			(end -0.508 0.3048)
			(stroke
				(width 0.1)
				(type default)
			)
			(layer "B.Fab")
		)
		(fp_line
			(start 0.508 -0.3048)
			(end 0.508 0.3048)
			(stroke
				(width 0.1)
				(type default)
			)
			(layer "B.Fab")
		)
		(fp_line
			(start -0.508 0.3048)
			(end -0.508 -0.3048)
			(stroke
				(width 0.1)
				(type default)
			)
			(layer "B.Fab")
		)
		(fp_line
			(start -0.508 -0.3048)
			(end 0.508 -0.3048)
			(stroke
				(width 0.1)
				(type default)
			)
			(layer "B.Fab")
		)
		(pad "1" smd rect
			(at 0.5334 0)
			(size 0.7112 0.6096)
			(layers "B.Cu" "B.Mask" "B.Paste")
			(net "MUX_USB_DP")
		)
		(pad "2" smd rect
			(at -0.5334 0)
			(size 0.7112 0.6096)
			(layers "B.Cu" "B.Mask" "B.Paste")
			(net "MAC_USB_DP")
		)
		(zone
			(layer "B.Cu")
			(hatch none 0.5)
			(connect_pads
				(clearance 0)
			)
			(min_thickness 0.25)
			(keepout
				(tracks allowed)
				(vias not_allowed)
				(pads allowed)
				(copperpour not_allowed)
				(footprints allowed)
			)
			(placement
				(enabled no)
				(sheetname "")
			)
			(fill
				(thermal_gap 0.5)
				(thermal_bridge_width 0.5)
				(island_removal_mode 0)
			)
			(polygon
				(pts
					(xy 90.1954 -47.612046) (xy 90.3478 -47.612046) (xy 90.3478 -48.221646) (xy 90.1954 -48.221646)
				)
			)
		)
	)
)
